(kicad_pcb
	(version 20241229)
	(generator "pcbnew")
	(generator_version "9.0")
	(general
		(thickness 1.294)
		(legacy_teardrops no)
	)
	(paper "A3")
	(title_block
		(title "Kintex 410T devboard")
		(date "2024-04-03")
		(rev "1.1.2")
		(comment 9 "footprints 789-794 of 975")
	)
	(layers
		(0 "F.Cu" mixed)
		(4 "In1.Cu" power)
		(6 "In2.Cu" power)
		(8 "In3.Cu" mixed)
		(10 "In4.Cu" power)
		(12 "In5.Cu" mixed)
		(14 "In6.Cu" power)
		(16 "In7.Cu" mixed)
		(18 "In8.Cu" power)
		(2 "B.Cu" mixed)
		(9 "F.Adhes" user "F.Adhesive")
		(11 "B.Adhes" user "B.Adhesive")
		(13 "F.Paste" user)
		(15 "B.Paste" user)
		(5 "F.SilkS" user "F.Silkscreen")
		(7 "B.SilkS" user "B.Silkscreen")
		(1 "F.Mask" user)
		(3 "B.Mask" user)
		(17 "Dwgs.User" user "User.Drawings")
		(19 "Cmts.User" user "User.Comments")
		(21 "Eco1.User" user "User.Eco1")
		(23 "Eco2.User" user "User.Eco2")
		(25 "Edge.Cuts" user)
		(27 "Margin" user)
		(31 "F.CrtYd" user "F.Courtyard")
		(29 "B.CrtYd" user "B.Courtyard")
		(35 "F.Fab" user)
		(33 "B.Fab" user)
	)
	(footprint "antmicro-footprints:R_0603_1608Metric"
		(layer "B.Cu")
		(at 248.601 176.7 90)
		(descr "Resistor SMD 0603")
		(tags "resistor SMD 0603")
		(property "Reference" "R52"
			(at 1.075 -0.626 270)
			(layer "B.SilkS")
			(effects
				(font
					(size 0.7 0.7)
					(thickness 0.15)
				)
				(justify left bottom mirror)
			)
		)
		(property "Value" "R_63R4_0603"
			(at 0 -1.6 270)
			(layer "B.Fab")
			(effects
				(font
					(size 0.7 0.7)
					(thickness 0.15)
				)
				(justify left bottom mirror)
			)
		)
		(property "Description" "SMD Chip Resistor"
			(at 0 0 90)
			(layer "F.Fab")
			(hide yes)
			(effects
				(font
					(size 1.27 1.27)
					(thickness 0.15)
				)
			)
		)
		(property "Author" "Antmicro"
			(at 425.301 -71.901 0)
			(layer "B.Fab")
			(hide yes)
			(effects
				(font
					(size 1 1)
					(thickness 0.15)
				)
				(justify mirror)
			)
		)
		(property "License" "Apache-2.0"
			(at 425.301 -71.901 0)
			(layer "B.Fab")
			(hide yes)
			(effects
				(font
					(size 1 1)
					(thickness 0.15)
				)
				(justify mirror)
			)
		)
		(property "MPN" "CR0603-FX-63R4ELF"
			(at 425.301 -71.901 0)
			(layer "B.Fab")
			(hide yes)
			(effects
				(font
					(size 1 1)
					(thickness 0.15)
				)
				(justify mirror)
			)
		)
		(property "Manufacturer" "Bourns"
			(at 425.301 -71.901 0)
			(layer "B.Fab")
			(hide yes)
			(effects
				(font
					(size 1 1)
					(thickness 0.15)
				)
				(justify mirror)
			)
		)
		(property "Tolerance" "1%"
			(at 425.301 -71.901 0)
			(layer "B.Fab")
			(hide yes)
			(effects
				(font
					(size 1 1)
					(thickness 0.15)
				)
				(justify mirror)
			)
		)
		(property "Val" "63R4"
			(at 425.301 -71.901 0)
			(layer "B.Fab")
			(hide yes)
			(effects
				(font
					(size 1 1)
					(thickness 0.15)
				)
				(justify mirror)
			)
		)
		(sheetname "Power supply")
		(sheetfile "power-supply.kicad_sch")
		(attr smd)
		(fp_line
			(start -0.15 -0.4)
			(end 0.15 -0.4)
			(stroke
				(width 0.15)
				(type solid)
			)
			(layer "B.SilkS")
		)
		(fp_line
			(start -0.15 0.4)
			(end 0.15 0.4)
			(stroke
				(width 0.15)
				(type solid)
			)
			(layer "B.SilkS")
		)
		(fp_rect
			(start -1.25 0.65)
			(end 1.25 -0.65)
			(stroke
				(width 0.05)
				(type solid)
			)
			(fill no)
			(layer "B.CrtYd")
		)
		(fp_rect
			(start -0.8 0.4)
			(end 0.8 -0.4)
			(stroke
				(width 0.15)
				(type solid)
			)
			(fill no)
			(layer "B.Fab")
		)
		(pad "1" smd roundrect
			(at -0.7 0 90)
			(size 0.8 1)
			(layers "B.Cu" "B.Mask" "B.Paste")
			(roundrect_rratio 0.2)
			(net 697 "/Power supply/VSS")
			(pintype "passive")
		)
		(pad "2" smd roundrect
			(at 0.7 0 90)
			(size 0.8 1)
			(layers "B.Cu" "B.Mask" "B.Paste")
			(roundrect_rratio 0.2)
			(net 885 "/Power supply/CLSA")
			(pintype "passive")
		)
	)
	(footprint "antmicro-footprints:C_0603_1608Metric"
		(layer "B.Cu")
		(at 201.5 147 90)
		(descr "Capacitor SMD 0603")
		(tags "capacitor 0603")
		(property "Reference" "C381"
			(at -1.5 1.375 90)
			(layer "B.SilkS")
			(effects
				(font
					(size 0.7 0.7)
					(thickness 0.15)
				)
				(justify right bottom mirror)
			)
		)
		(property "Value" "C_47u_0603"
			(at 0 -1.6 90)
			(layer "B.Fab")
			(effects
				(font
					(size 0.7 0.7)
					(thickness 0.15)
				)
				(justify right bottom mirror)
			)
		)
		(property "Description" "SMD Multilayer Ceramic Capacitor, 47 µF, 6.3 V, 0603 [1608 Metric], ± 20%, X5R, GRM Series"
			(at 0 0 90)
			(layer "F.Fab")
			(hide yes)
			(effects
				(font
					(size 1.27 1.27)
					(thickness 0.15)
				)
			)
		)
		(property "Author" "Antmicro"
			(at 348.5 -54.5 0)
			(layer "B.Fab")
			(hide yes)
			(effects
				(font
					(size 1 1)
					(thickness 0.15)
				)
				(justify mirror)
			)
		)
		(property "Dielectric" ""
			(at 348.5 -54.5 0)
			(layer "B.Fab")
			(hide yes)
			(effects
				(font
					(size 1 1)
					(thickness 0.15)
				)
				(justify mirror)
			)
		)
		(property "License" "Apache-2.0"
			(at 348.5 -54.5 0)
			(layer "B.Fab")
			(hide yes)
			(effects
				(font
					(size 1 1)
					(thickness 0.15)
				)
				(justify mirror)
			)
		)
		(property "MPN" "GRM188R60J476ME15D"
			(at 348.5 -54.5 0)
			(layer "B.Fab")
			(hide yes)
			(effects
				(font
					(size 1 1)
					(thickness 0.15)
				)
				(justify mirror)
			)
		)
		(property "Manufacturer" "Murata"
			(at 348.5 -54.5 0)
			(layer "B.Fab")
			(hide yes)
			(effects
				(font
					(size 1 1)
					(thickness 0.15)
				)
				(justify mirror)
			)
		)
		(property "Val" "47u"
			(at 348.5 -54.5 0)
			(layer "B.Fab")
			(hide yes)
			(effects
				(font
					(size 1 1)
					(thickness 0.15)
				)
				(justify mirror)
			)
		)
		(property "Voltage" ""
			(at 348.5 -54.5 0)
			(layer "B.Fab")
			(hide yes)
			(effects
				(font
					(size 1 1)
					(thickness 0.15)
				)
				(justify mirror)
			)
		)
		(sheetname "FPGA supply")
		(sheetfile "fpga-supply.kicad_sch")
		(attr smd)
		(fp_line
			(start -0.15 -0.4)
			(end 0.15 -0.4)
			(stroke
				(width 0.15)
				(type solid)
			)
			(layer "B.SilkS")
		)
		(fp_line
			(start -0.15 0.4)
			(end 0.15 0.4)
			(stroke
				(width 0.15)
				(type solid)
			)
			(layer "B.SilkS")
		)
		(fp_rect
			(start -1.25 0.65)
			(end 1.25 -0.65)
			(stroke
				(width 0.05)
				(type solid)
			)
			(fill no)
			(layer "B.CrtYd")
		)
		(fp_rect
			(start -0.8 0.4)
			(end 0.8 -0.4)
			(stroke
				(width 0.15)
				(type solid)
			)
			(fill no)
			(layer "B.Fab")
		)
		(pad "1" smd roundrect
			(at -0.7 0 90)
			(size 0.8 1)
			(layers "B.Cu" "B.Mask" "B.Paste")
			(roundrect_rratio 0.2)
			(net 1 "GND")
			(pintype "passive")
		)
		(pad "2" smd roundrect
			(at 0.7 0 90)
			(size 0.8 1)
			(layers "B.Cu" "B.Mask" "B.Paste")
			(roundrect_rratio 0.2)
			(net 650 "+1V0")
			(pintype "passive")
		)
	)
	(footprint "antmicro-footprints:R_0402_1005Metric"
		(layer "B.Cu")
		(at 153.2125 169.2 90)
		(descr "Resistor SMD 0402")
		(tags "resistor SMD 0402")
		(property "Reference" "R304"
			(at -0.725 0.3875 270)
			(layer "B.SilkS")
			(effects
				(font
					(size 0.7 0.7)
					(thickness 0.15)
				)
				(justify left bottom mirror)
			)
		)
		(property "Value" "R_0R_0402"
			(at 0 -1.4 270)
			(layer "B.Fab")
			(effects
				(font
					(size 0.7 0.7)
					(thickness 0.15)
				)
				(justify left bottom mirror)
			)
		)
		(property "Description" "SMD Chip Resistor, Jumper, 0 ohm, 100 mW, 0402 [1005 Metric], Thick Film, General Purpose"
			(at 0 0 90)
			(layer "F.Fab")
			(hide yes)
			(effects
				(font
					(size 1.27 1.27)
					(thickness 0.15)
				)
			)
		)
		(property "Author" "Antmicro"
			(at 322.4125 15.9875 0)
			(layer "B.Fab")
			(hide yes)
			(effects
				(font
					(size 1 1)
					(thickness 0.15)
				)
				(justify mirror)
			)
		)
		(property "Current" "1A"
			(at 322.4125 15.9875 0)
			(layer "B.Fab")
			(hide yes)
			(effects
				(font
					(size 1 1)
					(thickness 0.15)
				)
				(justify mirror)
			)
		)
		(property "DNP" "DNP"
			(at 322.4125 15.9875 0)
			(layer "B.Fab")
			(hide yes)
			(effects
				(font
					(size 1 1)
					(thickness 0.15)
				)
				(justify mirror)
			)
		)
		(property "License" "Apache-2.0"
			(at 322.4125 15.9875 0)
			(layer "B.Fab")
			(hide yes)
			(effects
				(font
					(size 1 1)
					(thickness 0.15)
				)
				(justify mirror)
			)
		)
		(property "MPN" "ERJ2GE0R00X"
			(at 322.4125 15.9875 0)
			(layer "B.Fab")
			(hide yes)
			(effects
				(font
					(size 1 1)
					(thickness 0.15)
				)
				(justify mirror)
			)
		)
		(property "Manufacturer" "Panasonic"
			(at 322.4125 15.9875 0)
			(layer "B.Fab")
			(hide yes)
			(effects
				(font
					(size 1 1)
					(thickness 0.15)
				)
				(justify mirror)
			)
		)
		(property "Tolerance" ""
			(at 322.4125 15.9875 0)
			(layer "B.Fab")
			(hide yes)
			(effects
				(font
					(size 1 1)
					(thickness 0.15)
				)
				(justify mirror)
			)
		)
		(property "Val" "0R"
			(at 322.4125 15.9875 0)
			(layer "B.Fab")
			(hide yes)
			(effects
				(font
					(size 1 1)
					(thickness 0.15)
				)
				(justify mirror)
			)
		)
		(property "dnp" ""
			(at 322.4125 15.9875 0)
			(layer "B.Fab")
			(hide yes)
			(effects
				(font
					(size 1 1)
					(thickness 0.15)
				)
				(justify mirror)
			)
		)
		(property "exclude_from_bom" ""
			(at 322.4125 15.9875 0)
			(layer "B.Fab")
			(hide yes)
			(effects
				(font
					(size 1 1)
					(thickness 0.15)
				)
				(justify mirror)
			)
		)
		(sheetname "DC-DC Converters")
		(sheetfile "dc-dc.kicad_sch")
		(attr smd exclude_from_bom)
		(fp_rect
			(start -0.925 0.47)
			(end 0.925 -0.47)
			(stroke
				(width 0.05)
				(type default)
			)
			(fill no)
			(layer "B.CrtYd")
		)
		(fp_rect
			(start -0.5 0.25)
			(end 0.5 -0.25)
			(stroke
				(width 0.15)
				(type solid)
			)
			(fill no)
			(layer "B.Fab")
		)
		(pad "1" smd roundrect
			(at -0.48 0 90)
			(size 0.59 0.64)
			(layers "B.Cu" "B.Mask" "B.Paste")
			(roundrect_rratio 0.25)
			(net 959 "/DC-DC Converters/FB1")
			(pintype "passive")
		)
		(pad "2" smd roundrect
			(at 0.48 0 90)
			(size 0.59 0.64)
			(layers "B.Cu" "B.Mask" "B.Paste")
			(roundrect_rratio 0.25)
			(net 1221 "/DC-DC Converters/SENSE_1V0_P")
			(pintype "passive")
		)
	)
	(footprint "antmicro-footprints:C_0402_1005Metric"
		(layer "B.Cu")
		(at 219.875 130.65 180)
		(descr "Capacitor SMD 0402")
		(tags "capacitor SMD 0402")
		(property "Reference" "C178"
			(at -1.475 0.45 0)
			(layer "B.SilkS")
			(effects
				(font
					(size 0.7 0.7)
					(thickness 0.15)
				)
				(justify left bottom mirror)
			)
		)
		(property "Value" "C_100n_0402"
			(at 0 -1.169 0)
			(layer "B.Fab")
			(effects
				(font
					(size 0.7 0.7)
					(thickness 0.15)
				)
				(justify left bottom mirror)
			)
		)
		(property "Description" "SMD Multilayer Ceramic Capacitor, 0.1 µF, 50 V, 0402 [1005 Metric], ± 10%, X5R, GRM Series"
			(at 0 0 180)
			(layer "F.Fab")
			(hide yes)
			(effects
				(font
					(size 1.27 1.27)
					(thickness 0.15)
				)
			)
		)
		(property "Author" "Antmicro"
			(at 439.75 261.3 0)
			(layer "B.Fab")
			(hide yes)
			(effects
				(font
					(size 1 1)
					(thickness 0.15)
				)
				(justify mirror)
			)
		)
		(property "Dielectric" "X5R"
			(at 439.75 261.3 0)
			(layer "B.Fab")
			(hide yes)
			(effects
				(font
					(size 1 1)
					(thickness 0.15)
				)
				(justify mirror)
			)
		)
		(property "License" "Apache-2.0"
			(at 439.75 261.3 0)
			(layer "B.Fab")
			(hide yes)
			(effects
				(font
					(size 1 1)
					(thickness 0.15)
				)
				(justify mirror)
			)
		)
		(property "MPN" "GRM155R61H104KE14D"
			(at 439.75 261.3 0)
			(layer "B.Fab")
			(hide yes)
			(effects
				(font
					(size 1 1)
					(thickness 0.15)
				)
				(justify mirror)
			)
		)
		(property "Manufacturer" "Murata"
			(at 439.75 261.3 0)
			(layer "B.Fab")
			(hide yes)
			(effects
				(font
					(size 1 1)
					(thickness 0.15)
				)
				(justify mirror)
			)
		)
		(property "Val" "100n"
			(at 439.75 261.3 0)
			(layer "B.Fab")
			(hide yes)
			(effects
				(font
					(size 1 1)
					(thickness 0.15)
				)
				(justify mirror)
			)
		)
		(property "Voltage" "50V"
			(at 439.75 261.3 0)
			(layer "B.Fab")
			(hide yes)
			(effects
				(font
					(size 1 1)
					(thickness 0.15)
				)
				(justify mirror)
			)
		)
		(sheetname "DRAM + SRAM")
		(sheetfile "ram.kicad_sch")
		(attr smd)
		(fp_rect
			(start -0.925 0.47)
			(end 0.925 -0.47)
			(stroke
				(width 0.05)
				(type default)
			)
			(fill no)
			(layer "B.CrtYd")
		)
		(fp_line
			(start 0.504 0.25)
			(end 0.504 -0.248)
			(stroke
				(width 0.15)
				(type solid)
			)
			(layer "B.Fab")
		)
		(fp_line
			(start 0.504 -0.248)
			(end -0.494 -0.248)
			(stroke
				(width 0.15)
				(type solid)
			)
			(layer "B.Fab")
		)
		(fp_line
			(start -0.494 0.25)
			(end 0.504 0.25)
			(stroke
				(width 0.15)
				(type solid)
			)
			(layer "B.Fab")
		)
		(fp_line
			(start -0.494 -0.248)
			(end -0.494 0.25)
			(stroke
				(width 0.15)
				(type solid)
			)
			(layer "B.Fab")
		)
		(pad "1" smd roundrect
			(at -0.48 0 180)
			(size 0.59 0.64)
			(layers "B.Cu" "B.Mask" "B.Paste")
			(roundrect_rratio 0.25)
			(net 1 "GND")
			(pintype "passive")
		)
		(pad "2" smd roundrect
			(at 0.48 0 180)
			(size 0.59 0.64)
			(layers "B.Cu" "B.Mask" "B.Paste")
			(roundrect_rratio 0.25)
			(net 24 "+3V3")
			(pintype "passive")
		)
	)
	(footprint "antmicro-footprints:R_0402_1005Metric"
		(layer "B.Cu")
		(at 189.36 84.8 90)
		(descr "Resistor SMD 0402")
		(tags "resistor SMD 0402")
		(property "Reference" "R136"
			(at -0.725 0.4 270)
			(layer "B.SilkS")
			(effects
				(font
					(size 0.7 0.7)
					(thickness 0.15)
				)
				(justify left bottom mirror)
			)
		)
		(property "Value" "R_100R_0402"
			(at 0 -1.4 270)
			(layer "B.Fab")
			(effects
				(font
					(size 0.7 0.7)
					(thickness 0.15)
				)
				(justify left bottom mirror)
			)
		)
		(property "Description" "SMD Chip Resistor, 100 ohm, ± 1%, 62.5 mW, 0402 [1005 Metric], Thick Film, General Purpose"
			(at 0 0 90)
			(layer "F.Fab")
			(hide yes)
			(effects
				(font
					(size 1.27 1.27)
					(thickness 0.15)
				)
			)
		)
		(property "Author" "Antmicro"
			(at 274.16 -104.56 0)
			(layer "B.Fab")
			(hide yes)
			(effects
				(font
					(size 1 1)
					(thickness 0.15)
				)
				(justify mirror)
			)
		)
		(property "License" "Apache-2.0"
			(at 274.16 -104.56 0)
			(layer "B.Fab")
			(hide yes)
			(effects
				(font
					(size 1 1)
					(thickness 0.15)
				)
				(justify mirror)
			)
		)
		(property "MPN" "CR0402-FX-1000GLF"
			(at 274.16 -104.56 0)
			(layer "B.Fab")
			(hide yes)
			(effects
				(font
					(size 1 1)
					(thickness 0.15)
				)
				(justify mirror)
			)
		)
		(property "Manufacturer" "Bourns"
			(at 274.16 -104.56 0)
			(layer "B.Fab")
			(hide yes)
			(effects
				(font
					(size 1 1)
					(thickness 0.15)
				)
				(justify mirror)
			)
		)
		(property "Tolerance" "1%"
			(at 274.16 -104.56 0)
			(layer "B.Fab")
			(hide yes)
			(effects
				(font
					(size 1 1)
					(thickness 0.15)
				)
				(justify mirror)
			)
		)
		(property "Val" "100R"
			(at 274.16 -104.56 0)
			(layer "B.Fab")
			(hide yes)
			(effects
				(font
					(size 1 1)
					(thickness 0.15)
				)
				(justify mirror)
			)
		)
		(sheetname "User GPIO + LED + button + DIP switch")
		(sheetfile "user-gpio.kicad_sch")
		(attr smd)
		(fp_rect
			(start -0.925 0.47)
			(end 0.925 -0.47)
			(stroke
				(width 0.05)
				(type default)
			)
			(fill no)
			(layer "B.CrtYd")
		)
		(fp_rect
			(start -0.5 0.25)
			(end 0.5 -0.25)
			(stroke
				(width 0.15)
				(type solid)
			)
			(fill no)
			(layer "B.Fab")
		)
		(pad "1" smd roundrect
			(at -0.48 0 90)
			(size 0.59 0.64)
			(layers "B.Cu" "B.Mask" "B.Paste")
			(roundrect_rratio 0.25)
			(net 826 "/User GPIO + LED + button + DIP switch/CW_20PIN_MOSI")
			(pintype "passive")
		)
		(pad "2" smd roundrect
			(at 0.48 0 90)
			(size 0.59 0.64)
			(layers "B.Cu" "B.Mask" "B.Paste")
			(roundrect_rratio 0.25)
			(net 476 "/FPGA Bank 12 & 13/CW_HEADER.MOSI")
			(pintype "passive")
		)
	)
	(footprint "antmicro-footprints:C_0402_1005Metric"
		(layer "B.Cu")
		(at 194.775 128.775 180)
		(descr "Capacitor SMD 0402")
		(tags "capacitor SMD 0402")
		(property "Reference" "C136"
			(at -24.475 28.75 0)
			(layer "B.SilkS")
			(effects
				(font
					(size 0.7 0.7)
					(thickness 0.15)
				)
				(justify left bottom mirror)
			)
		)
		(property "Value" "C_100n_0402"
			(at 0 -1.169 0)
			(layer "B.Fab")
			(effects
				(font
					(size 0.7 0.7)
					(thickness 0.15)
				)
				(justify left bottom mirror)
			)
		)
		(property "Description" "SMD Multilayer Ceramic Capacitor, 0.1 µF, 50 V, 0402 [1005 Metric], ± 10%, X5R, GRM Series"
			(at 0 0 180)
			(layer "F.Fab")
			(hide yes)
			(effects
				(font
					(size 1.27 1.27)
					(thickness 0.15)
				)
			)
		)
		(property "Author" "Antmicro"
			(at 389.55 257.55 0)
			(layer "B.Fab")
			(hide yes)
			(effects
				(font
					(size 1 1)
					(thickness 0.15)
				)
				(justify mirror)
			)
		)
		(property "Dielectric" "X5R"
			(at 389.55 257.55 0)
			(layer "B.Fab")
			(hide yes)
			(effects
				(font
					(size 1 1)
					(thickness 0.15)
				)
				(justify mirror)
			)
		)
		(property "License" "Apache-2.0"
			(at 389.55 257.55 0)
			(layer "B.Fab")
			(hide yes)
			(effects
				(font
					(size 1 1)
					(thickness 0.15)
				)
				(justify mirror)
			)
		)
		(property "MPN" "GRM155R61H104KE14D"
			(at 389.55 257.55 0)
			(layer "B.Fab")
			(hide yes)
			(effects
				(font
					(size 1 1)
					(thickness 0.15)
				)
				(justify mirror)
			)
		)
		(property "Manufacturer" "Murata"
			(at 389.55 257.55 0)
			(layer "B.Fab")
			(hide yes)
			(effects
				(font
					(size 1 1)
					(thickness 0.15)
				)
				(justify mirror)
			)
		)
		(property "Val" "100n"
			(at 389.55 257.55 0)
			(layer "B.Fab")
			(hide yes)
			(effects
				(font
					(size 1 1)
					(thickness 0.15)
				)
				(justify mirror)
			)
		)
		(property "Voltage" "50V"
			(at 389.55 257.55 0)
			(layer "B.Fab")
			(hide yes)
			(effects
				(font
					(size 1 1)
					(thickness 0.15)
				)
				(justify mirror)
			)
		)
		(sheetname "FPGA supply")
		(sheetfile "fpga-supply.kicad_sch")
		(attr smd)
		(fp_rect
			(start -0.925 0.47)
			(end 0.925 -0.47)
			(stroke
				(width 0.05)
				(type default)
			)
			(fill no)
			(layer "B.CrtYd")
		)
		(fp_line
			(start 0.504 0.25)
			(end 0.504 -0.248)
			(stroke
				(width 0.15)
				(type solid)
			)
			(layer "B.Fab")
		)
		(fp_line
			(start 0.504 -0.248)
			(end -0.494 -0.248)
			(stroke
				(width 0.15)
				(type solid)
			)
			(layer "B.Fab")
		)
		(fp_line
			(start -0.494 0.25)
			(end 0.504 0.25)
			(stroke
				(width 0.15)
				(type solid)
			)
			(layer "B.Fab")
		)
		(fp_line
			(start -0.494 -0.248)
			(end -0.494 0.25)
			(stroke
				(width 0.15)
				(type solid)
			)
			(layer "B.Fab")
		)
		(pad "1" smd roundrect
			(at -0.48 0 180)
			(size 0.59 0.64)
			(layers "B.Cu" "B.Mask" "B.Paste")
			(roundrect_rratio 0.25)
			(net 1 "GND")
			(pintype "passive")
		)
		(pad "2" smd roundrect
			(at 0.48 0 180)
			(size 0.59 0.64)
			(layers "B.Cu" "B.Mask" "B.Paste")
			(roundrect_rratio 0.25)
			(net 650 "+1V0")
			(pintype "passive")
		)
	)
)
